(kicad_pcb
	(version 20260206)
	(generator "pcbnew")
	(generator_version "10.0")
	(general
		(thickness 1.6)
		(legacy_teardrops no)
	)
	(paper "A4")
	(title_block
		(title "15969-1a.1015WZS0858.brd")
		(comment 1 "Tioga Pass / footprints 137-144 of 295")
	)
	(layers
		(0 "F.Cu" signal "TOP")
		(4 "In1.Cu" signal "L2GND")
		(6 "In2.Cu" signal "L3")
		(8 "In3.Cu" signal "L4")
		(10 "In4.Cu" signal "L5GND")
		(2 "B.Cu" signal "BOTTOM")
		(9 "F.Adhes" user "F.Adhesive")
		(11 "B.Adhes" user "B.Adhesive")
		(13 "F.Paste" user "Package Geometry/Pastemask Top")
		(15 "B.Paste" user "Package Geometry/Pastemask Bottom")
		(5 "F.SilkS" user "Ref Des/Silkscreen Top")
		(7 "B.SilkS" user "Ref Des/Silkscreen Bottom")
		(1 "F.Mask" user "Board Geometry/Soldermask Top")
		(3 "B.Mask" user "Board Geometry/Soldermask Bottom")
		(17 "Dwgs.User" user "User.Drawings")
		(19 "Cmts.User" user "User.Comments")
		(21 "Eco1.User" user "User.Eco1")
		(23 "Eco2.User" user "User.Eco2")
		(25 "Edge.Cuts" user "Board Geometry/Outline")
		(27 "Margin" user)
		(31 "F.CrtYd" user "Package Geometry/Place Bound Top")
		(29 "B.CrtYd" user "Package Geometry/Place Bound Bottom")
		(35 "F.Fab" user "Ref Des/Assembly Top")
		(33 "B.Fab" user "Ref Des/Assembly Bottom")
	)
	(footprint ""
		(layer "F.Cu")
		(at 125.1458 2.6416 90)
		(property "Reference" "R142"
			(at 0 0 90)
			(layer "F.SilkS")
			(hide yes)
			(effects
				(font
					(size 1.27 1.27)
				)
			)
		)
		(property "Value" "10KR2F-2-GP"
			(at 0.064008 -3.993896 90)
			(unlocked yes)
			(layer "F.Fab")
			(hide yes)
			(effects
				(font
					(size 1.016 1.016)
					(thickness 0.1524)
				)
			)
		)
		(property "Device Type" "R402H16"
			(at 0.064008 -5.517896 90)
			(unlocked yes)
			(layer "F.Fab")
			(hide yes)
			(effects
				(font
					(size 1.016 1.016)
					(thickness 0.1524)
				)
			)
		)
		(duplicate_pad_numbers_are_jumpers no)
		(fp_line
			(start 0.508 -0.9398)
			(end -0.508 -0.9398)
			(stroke
				(width 0.1524)
				(type default)
			)
			(layer "F.SilkS")
		)
		(fp_line
			(start -0.508 -0.9398)
			(end -0.508 0.9398)
			(stroke
				(width 0.1524)
				(type default)
			)
			(layer "F.SilkS")
		)
		(fp_rect
			(start -0.508 0.9398)
			(end 0.508 -0.9398)
			(stroke
				(width 0)
				(type default)
			)
			(fill no)
			(layer "F.CrtYd")
		)
		(fp_rect
			(start -0.508 0.9398)
			(end 0.508 -0.9398)
			(stroke
				(width 0)
				(type default)
			)
			(fill no)
			(layer "F.Fab")
		)
		(pad "1" smd custom
			(at 0 -0.4445 90)
			(size 0.1397 0.1397)
			(layers "F.Cu" "F.Mask" "F.Paste")
			(net "P3V3_STBY")
			(options
				(clearance outline)
				(anchor circle)
			)
			(primitives
				(gr_poly
					(pts
						(arc
							(start -0.1778 -0.2794)
							(mid -0.249642 -0.249642)
							(end -0.2794 -0.1778)
						)
						(arc
							(start -0.2794 0.1778)
							(mid -0.249642 0.249642)
							(end -0.1778 0.2794)
						)
						(arc
							(start 0.1778 0.2794)
							(mid 0.249642 0.249642)
							(end 0.2794 0.1778)
						)
						(arc
							(start 0.2794 -0.1778)
							(mid 0.249642 -0.249642)
							(end 0.1778 -0.2794)
						)
					)
					(width 0)
					(fill yes)
				)
			)
		)
		(pad "2" smd custom
			(at 0 0.4445 90)
			(size 0.1397 0.1397)
			(layers "F.Cu" "F.Mask" "F.Paste")
			(net "GPIO_P_IO1_6")
			(options
				(clearance outline)
				(anchor circle)
			)
			(primitives
				(gr_poly
					(pts
						(arc
							(start -0.1778 -0.2794)
							(mid -0.249642 -0.249642)
							(end -0.2794 -0.1778)
						)
						(arc
							(start -0.2794 0.1778)
							(mid -0.249642 0.249642)
							(end -0.1778 0.2794)
						)
						(arc
							(start 0.1778 0.2794)
							(mid 0.249642 0.249642)
							(end 0.2794 0.1778)
						)
						(arc
							(start 0.2794 -0.1778)
							(mid 0.249642 -0.249642)
							(end 0.1778 -0.2794)
						)
					)
					(width 0)
					(fill yes)
				)
			)
		)
	)
	(footprint ""
		(layer "F.Cu")
		(at 17.7292 -13.1572 90)
		(property "Reference" "PL1"
			(at 0 0 90)
			(layer "F.SilkS")
			(hide yes)
			(effects
				(font
					(size 1.27 1.27)
				)
			)
		)
		(property "Value" "BLM21PG220SN1DGP"
			(at 0.0254 -5.6896 90)
			(unlocked yes)
			(layer "F.Fab")
			(hide yes)
			(effects
				(font
					(size 1.016 1.016)
					(thickness 0.1524)
				)
			)
		)
		(property "Device Type" "L20125H42"
			(at 0.0254 -7.5946 90)
			(unlocked yes)
			(layer "F.Fab")
			(hide yes)
			(effects
				(font
					(size 1.016 1.016)
					(thickness 0.1524)
				)
			)
		)
		(duplicate_pad_numbers_are_jumpers no)
		(fp_line
			(start 0.9144 -1.7018)
			(end -0.9144 -1.7018)
			(stroke
				(width 0.1524)
				(type default)
			)
			(layer "F.SilkS")
		)
		(fp_line
			(start -0.9144 -1.7018)
			(end -0.9144 1.7018)
			(stroke
				(width 0.1524)
				(type default)
			)
			(layer "F.SilkS")
		)
		(fp_line
			(start 0.9144 1.7018)
			(end 0.9144 -1.7018)
			(stroke
				(width 0.1524)
				(type default)
			)
			(layer "F.SilkS")
		)
		(fp_line
			(start -0.9144 1.7018)
			(end 0.9144 1.7018)
			(stroke
				(width 0.1524)
				(type default)
			)
			(layer "F.SilkS")
		)
		(fp_rect
			(start -1.0033 1.778)
			(end 1.0033 -1.778)
			(stroke
				(width 0)
				(type default)
			)
			(fill no)
			(layer "F.CrtYd")
		)
		(fp_poly
			(pts
				(xy -1.0033 -1.778) (xy 1.0033 -1.778) (xy 1.0033 1.778) (xy -1.0033 1.778)
			)
			(stroke
				(width 0)
				(type default)
			)
			(fill no)
			(layer "F.Fab")
		)
		(pad "1" smd rect
			(at 0 -0.9652 90)
			(size 1.397 1.143)
			(layers "F.Cu" "F.Mask" "F.Paste")
			(net "P12V")
		)
		(pad "2" smd rect
			(at 0 0.9652 90)
			(size 1.397 1.143)
			(layers "F.Cu" "F.Mask" "F.Paste")
			(net "P3V3_VIN")
		)
	)
	(footprint ""
		(layer "F.Cu")
		(at 82.1436 -20.8788 180)
		(property "Reference" "R65"
			(at 0 0 180)
			(layer "F.SilkS")
			(hide yes)
			(effects
				(font
					(size 1.27 1.27)
				)
			)
		)
		(property "Value" "8K2R2F-1-GP"
			(at 0.064008 -3.993896 180)
			(unlocked yes)
			(layer "F.Fab")
			(hide yes)
			(effects
				(font
					(size 1.016 1.016)
					(thickness 0.1524)
				)
			)
		)
		(property "Device Type" "R402H16"
			(at 0.064008 -5.517896 180)
			(unlocked yes)
			(layer "F.Fab")
			(hide yes)
			(effects
				(font
					(size 1.016 1.016)
					(thickness 0.1524)
				)
			)
		)
		(duplicate_pad_numbers_are_jumpers no)
		(fp_line
			(start 0.508 -0.9398)
			(end -0.508 -0.9398)
			(stroke
				(width 0.1524)
				(type default)
			)
			(layer "F.SilkS")
		)
		(fp_line
			(start -0.508 -0.9398)
			(end -0.508 0.9398)
			(stroke
				(width 0.1524)
				(type default)
			)
			(layer "F.SilkS")
		)
		(fp_rect
			(start -0.508 0.9398)
			(end 0.508 -0.9398)
			(stroke
				(width 0)
				(type default)
			)
			(fill no)
			(layer "F.CrtYd")
		)
		(fp_rect
			(start -0.508 0.9398)
			(end 0.508 -0.9398)
			(stroke
				(width 0)
				(type default)
			)
			(fill no)
			(layer "F.Fab")
		)
		(pad "1" smd custom
			(at 0 -0.4445 180)
			(size 0.1397 0.1397)
			(layers "F.Cu" "F.Mask" "F.Paste")
			(net "P12V")
			(options
				(clearance outline)
				(anchor circle)
			)
			(primitives
				(gr_poly
					(pts
						(arc
							(start -0.1778 -0.2794)
							(mid -0.249642 -0.249642)
							(end -0.2794 -0.1778)
						)
						(arc
							(start -0.2794 0.1778)
							(mid -0.249642 0.249642)
							(end -0.1778 0.2794)
						)
						(arc
							(start 0.1778 0.2794)
							(mid 0.249642 0.249642)
							(end 0.2794 0.1778)
						)
						(arc
							(start 0.2794 -0.1778)
							(mid 0.249642 -0.249642)
							(end 0.1778 -0.2794)
						)
					)
					(width 0)
					(fill yes)
				)
			)
		)
		(pad "2" smd custom
			(at 0 0.4445 180)
			(size 0.1397 0.1397)
			(layers "F.Cu" "F.Mask" "F.Paste")
			(net "RESET_IN")
			(options
				(clearance outline)
				(anchor circle)
			)
			(primitives
				(gr_poly
					(pts
						(arc
							(start -0.1778 -0.2794)
							(mid -0.249642 -0.249642)
							(end -0.2794 -0.1778)
						)
						(arc
							(start -0.2794 0.1778)
							(mid -0.249642 0.249642)
							(end -0.1778 0.2794)
						)
						(arc
							(start 0.1778 0.2794)
							(mid 0.249642 0.249642)
							(end 0.2794 0.1778)
						)
						(arc
							(start 0.2794 -0.1778)
							(mid 0.249642 -0.249642)
							(end 0.1778 -0.2794)
						)
					)
					(width 0)
					(fill yes)
				)
			)
		)
	)
	(footprint ""
		(layer "F.Cu")
		(at 17.675098 -20.287742 -135)
		(property "Reference" "C47"
			(at 0 0 225)
			(layer "F.SilkS")
			(hide yes)
			(effects
				(font
					(size 1.27 1.27)
				)
			)
		)
		(property "Value" "SCD1U25V2KX-2-GP"
			(at 1.181083 -2.705137 225)
			(unlocked yes)
			(layer "F.Fab")
			(hide yes)
			(effects
				(font
					(size 1.016 1.016)
					(thickness 0.1524)
				)
			)
		)
		(property "Device Type" "C402H22"
			(at 1.181083 -4.229266 225)
			(unlocked yes)
			(layer "F.Fab")
			(hide yes)
			(effects
				(font
					(size 1.016 1.016)
					(thickness 0.1524)
				)
			)
		)
		(duplicate_pad_numbers_are_jumpers no)
		(fp_poly
			(pts
				(xy -0.43195 -0.952553) (xy 0.43165 -0.952554) (xy 0.431649 0.952446) (xy -0.43195 0.952446)
			)
			(stroke
				(width 0)
				(type default)
			)
			(fill no)
			(layer "F.CrtYd")
		)
		(fp_poly
			(pts
				(xy -0.43195 -0.952553) (xy 0.43165 -0.952554) (xy 0.431649 0.952446) (xy -0.43195 0.952446)
			)
			(stroke
				(width 0)
				(type default)
			)
			(fill no)
			(layer "F.Fab")
		)
		(pad "1" smd custom
			(at 0 -0.4445 225)
			(size 0.1524 0.1524)
			(layers "F.Cu" "F.Mask" "F.Paste")
			(net "SLOT2_P12V_SENSE_VP_R")
			(options
				(clearance outline)
				(anchor circle)
			)
			(primitives
				(gr_poly
					(pts
						(arc
							(start 0.3048 -0.2032)
							(mid 0.275042 -0.275042)
							(end 0.2032 -0.3048)
						)
						(arc
							(start -0.2032 -0.3048)
							(mid -0.275042 -0.275042)
							(end -0.3048 -0.2032)
						)
						(arc
							(start -0.3048 0.2032)
							(mid -0.275042 0.275042)
							(end -0.2032 0.3048)
						)
						(arc
							(start 0.2032 0.3048)
							(mid 0.275042 0.275042)
							(end 0.3048 0.2032)
						)
					)
					(width 0)
					(fill yes)
				)
			)
		)
		(pad "2" smd custom
			(at 0 0.4445 225)
			(size 0.1524 0.1524)
			(layers "F.Cu" "F.Mask" "F.Paste")
			(net "SLOT2_P12V_SENSE_VN_R")
			(options
				(clearance outline)
				(anchor circle)
			)
			(primitives
				(gr_poly
					(pts
						(arc
							(start 0.3048 -0.2032)
							(mid 0.275042 -0.275042)
							(end 0.2032 -0.3048)
						)
						(arc
							(start -0.2032 -0.3048)
							(mid -0.275042 -0.275042)
							(end -0.3048 -0.2032)
						)
						(arc
							(start -0.3048 0.2032)
							(mid -0.275042 0.275042)
							(end -0.2032 0.3048)
						)
						(arc
							(start 0.2032 0.3048)
							(mid 0.275042 0.275042)
							(end 0.3048 0.2032)
						)
					)
					(width 0)
					(fill yes)
				)
			)
		)
	)
	(footprint ""
		(layer "F.Cu")
		(at 23.1394 -31.9532 180)
		(property "Reference" "C60"
			(at 0 0 180)
			(layer "F.SilkS")
			(hide yes)
			(effects
				(font
					(size 1.27 1.27)
				)
			)
		)
		(property "Value" "SC22U16V5MX-4-GP"
			(at -0.0762 -6.1214 180)
			(unlocked yes)
			(layer "F.Fab")
			(hide yes)
			(effects
				(font
					(size 1.016 1.016)
					(thickness 0.1524)
				)
			)
		)
		(property "Device Type" "C805H58"
			(at -0.0762 -8.1534 180)
			(unlocked yes)
			(layer "F.Fab")
			(hide yes)
			(effects
				(font
					(size 1.016 1.016)
					(thickness 0.1524)
				)
			)
		)
		(duplicate_pad_numbers_are_jumpers no)
		(fp_line
			(start 0.635 0)
			(end -0.635 0)
			(stroke
				(width 0.508)
				(type default)
			)
			(layer "F.SilkS")
		)
		(fp_rect
			(start -0.9652 1.778)
			(end 0.9652 -1.778)
			(stroke
				(width 0)
				(type default)
			)
			(fill no)
			(layer "F.CrtYd")
		)
		(fp_poly
			(pts
				(xy -0.9652 -1.778) (xy 0.9652 -1.778) (xy 0.9652 1.778) (xy -0.9652 1.778)
			)
			(stroke
				(width 0)
				(type default)
			)
			(fill no)
			(layer "F.Fab")
		)
		(pad "1" smd rect
			(at 0 -0.9652 180)
			(size 1.397 1.143)
			(layers "F.Cu" "F.Mask" "F.Paste")
			(net "P12V_SLOT3")
		)
		(pad "2" smd rect
			(at 0 0.9652 180)
			(size 1.397 1.143)
			(layers "F.Cu" "F.Mask" "F.Paste")
			(net "GND")
		)
	)
	(footprint ""
		(layer "F.Cu")
		(at 97.525078 -22.008846 180)
		(property "Reference" "U8"
			(at 0 0 180)
			(layer "F.SilkS")
			(hide yes)
			(effects
				(font
					(size 1.27 1.27)
				)
			)
		)
		(property "Value" "SN74LVC1G08DCKR-GP"
			(at -2.3368 -8.6868 180)
			(unlocked yes)
			(layer "F.Fab")
			(hide yes)
			(effects
				(font
					(size 1.016 1.016)
					(thickness 0.1524)
				)
			)
		)
		(property "Device Type" "SC70-5H44"
			(at -2.3114 -10.414 180)
			(unlocked yes)
			(layer "F.Fab")
			(hide yes)
			(effects
				(font
					(size 1.016 1.016)
					(thickness 0.1524)
				)
			)
		)
		(duplicate_pad_numbers_are_jumpers no)
		(fp_line
			(start 1.3843 -1.8034)
			(end 1.3843 -1.1176)
			(stroke
				(width 0.3302)
				(type default)
			)
			(layer "F.SilkS")
		)
		(fp_line
			(start 1.27 1.7018)
			(end -1.27 1.7018)
			(stroke
				(width 0.1524)
				(type default)
			)
			(layer "F.SilkS")
		)
		(fp_line
			(start 1.27 -1.7018)
			(end 1.27 1.7018)
			(stroke
				(width 0.1524)
				(type default)
			)
			(layer "F.SilkS")
		)
		(fp_line
			(start 0.6604 -1.8034)
			(end 1.3843 -1.8034)
			(stroke
				(width 0.3302)
				(type default)
			)
			(layer "F.SilkS")
		)
		(fp_line
			(start -1.27 1.7018)
			(end -1.27 -1.7018)
			(stroke
				(width 0.1524)
				(type default)
			)
			(layer "F.SilkS")
		)
		(fp_line
			(start -1.27 -1.7018)
			(end 1.27 -1.7018)
			(stroke
				(width 0.1524)
				(type default)
			)
			(layer "F.SilkS")
		)
		(fp_rect
			(start -1.524 1.9558)
			(end 1.524 -1.9558)
			(stroke
				(width 0)
				(type default)
			)
			(fill no)
			(layer "F.CrtYd")
		)
		(fp_poly
			(pts
				(xy -1.524 -1.9558) (xy 1.524 -1.9558) (xy 1.524 1.9558) (xy -1.524 1.9558)
			)
			(stroke
				(width 0)
				(type default)
			)
			(fill no)
			(layer "F.Fab")
		)
		(pad "1" smd rect
			(at 0.65024 -0.8255 180)
			(size 0.4064 1.2192)
			(layers "F.Cu" "F.Mask" "F.Paste")
			(net "PERST_O_1_R")
		)
		(pad "2" smd rect
			(at 0 -0.8255 180)
			(size 0.4064 1.2192)
			(layers "F.Cu" "F.Mask" "F.Paste")
			(net "RESET_O_2_R")
		)
		(pad "3" smd rect
			(at -0.65024 -0.8255 180)
			(size 0.4064 1.2192)
			(layers "F.Cu" "F.Mask" "F.Paste")
			(net "GND")
		)
		(pad "4" smd rect
			(at -0.65024 0.8255 180)
			(size 0.4064 1.2192)
			(layers "F.Cu" "F.Mask" "F.Paste")
			(net "PERST_N_1")
		)
		(pad "5" smd rect
			(at 0.65024 0.8255 180)
			(size 0.4064 1.2192)
			(layers "F.Cu" "F.Mask" "F.Paste")
			(net "P3V3_STBY")
		)
	)
	(footprint ""
		(layer "F.Cu")
		(at 119.5832 -8.0772 90)
		(property "Reference" "R136"
			(at 0 0 90)
			(layer "F.SilkS")
			(hide yes)
			(effects
				(font
					(size 1.27 1.27)
				)
			)
		)
		(property "Value" "10KR2F-2-GP"
			(at 0.064008 -3.993896 90)
			(unlocked yes)
			(layer "F.Fab")
			(hide yes)
			(effects
				(font
					(size 1.016 1.016)
					(thickness 0.1524)
				)
			)
		)
		(property "Device Type" "R402H16"
			(at 0.064008 -5.517896 90)
			(unlocked yes)
			(layer "F.Fab")
			(hide yes)
			(effects
				(font
					(size 1.016 1.016)
					(thickness 0.1524)
				)
			)
		)
		(duplicate_pad_numbers_are_jumpers no)
		(fp_line
			(start 0.508 -0.9398)
			(end -0.508 -0.9398)
			(stroke
				(width 0.1524)
				(type default)
			)
			(layer "F.SilkS")
		)
		(fp_line
			(start -0.508 -0.9398)
			(end -0.508 0.9398)
			(stroke
				(width 0.1524)
				(type default)
			)
			(layer "F.SilkS")
		)
		(fp_rect
			(start -0.508 0.9398)
			(end 0.508 -0.9398)
			(stroke
				(width 0)
				(type default)
			)
			(fill no)
			(layer "F.CrtYd")
		)
		(fp_rect
			(start -0.508 0.9398)
			(end 0.508 -0.9398)
			(stroke
				(width 0)
				(type default)
			)
			(fill no)
			(layer "F.Fab")
		)
		(pad "1" smd custom
			(at 0 -0.4445 90)
			(size 0.1397 0.1397)
			(layers "F.Cu" "F.Mask" "F.Paste")
			(net "P3V3_STBY")
			(options
				(clearance outline)
				(anchor circle)
			)
			(primitives
				(gr_poly
					(pts
						(arc
							(start -0.1778 -0.2794)
							(mid -0.249642 -0.249642)
							(end -0.2794 -0.1778)
						)
						(arc
							(start -0.2794 0.1778)
							(mid -0.249642 0.249642)
							(end -0.1778 0.2794)
						)
						(arc
							(start 0.1778 0.2794)
							(mid 0.249642 0.249642)
							(end 0.2794 0.1778)
						)
						(arc
							(start 0.2794 -0.1778)
							(mid 0.249642 -0.249642)
							(end 0.1778 -0.2794)
						)
					)
					(width 0)
					(fill yes)
				)
			)
		)
		(pad "2" smd custom
			(at 0 0.4445 90)
			(size 0.1397 0.1397)
			(layers "F.Cu" "F.Mask" "F.Paste")
			(net "GPIO_P_IO1_3")
			(options
				(clearance outline)
				(anchor circle)
			)
			(primitives
				(gr_poly
					(pts
						(arc
							(start -0.1778 -0.2794)
							(mid -0.249642 -0.249642)
							(end -0.2794 -0.1778)
						)
						(arc
							(start -0.2794 0.1778)
							(mid -0.249642 0.249642)
							(end -0.1778 0.2794)
						)
						(arc
							(start 0.1778 0.2794)
							(mid 0.249642 0.249642)
							(end 0.2794 0.1778)
						)
						(arc
							(start 0.2794 -0.1778)
							(mid 0.249642 -0.249642)
							(end 0.1778 -0.2794)
						)
					)
					(width 0)
					(fill yes)
				)
			)
		)
	)
	(footprint ""
		(layer "F.Cu")
		(at 15.1384 -23.5458 180)
		(property "Reference" "R90"
			(at 0 0 180)
			(layer "F.SilkS")
			(hide yes)
			(effects
				(font
					(size 1.27 1.27)
				)
			)
		)
		(property "Value" "D001R6F-L-GP"
			(at -0.127 -3.7338 180)
			(unlocked yes)
			(layer "F.Fab")
			(hide yes)
			(effects
				(font
					(size 1.016 1.016)
					(thickness 0.1524)
				)
			)
		)
		(property "Device Type" "R1206H36"
			(at -0.127 -5.2578 180)
			(unlocked yes)
			(layer "F.Fab")
			(hide yes)
			(effects
				(font
					(size 1.016 1.016)
					(thickness 0.1524)
				)
			)
		)
		(duplicate_pad_numbers_are_jumpers no)
		(fp_line
			(start 1.016 2.2352)
			(end -1.016 2.2352)
			(stroke
				(width 0.1524)
				(type default)
			)
			(layer "F.SilkS")
		)
		(fp_line
			(start 1.016 -2.2352)
			(end 1.016 2.2352)
			(stroke
				(width 0.1524)
				(type default)
			)
			(layer "F.SilkS")
		)
		(fp_line
			(start -1.016 2.2352)
			(end -1.016 -2.2352)
			(stroke
				(width 0.1524)
				(type default)
			)
			(layer "F.SilkS")
		)
		(fp_line
			(start -1.016 -2.2352)
			(end 1.016 -2.2352)
			(stroke
				(width 0.1524)
				(type default)
			)
			(layer "F.SilkS")
		)
		(fp_rect
			(start -0.8001 1.6002)
			(end 0.8001 -1.6002)
			(stroke
				(width 0)
				(type default)
			)
			(fill no)
			(layer "F.CrtYd")
		)
		(fp_poly
			(pts
				(xy -1.0922 2.3114) (xy -1.0922 -2.3114) (xy 1.0922 -2.3114) (xy 1.0922 1.5875) (xy 0.8001 1.5875)
				(xy 0.8001 -1.6002) (xy -0.8001 -1.6002) (xy -0.8001 1.6002) (xy 1.0922 1.6002) (xy 1.0922 2.3114)
			)
			(stroke
				(width 0)
				(type default)
			)
			(fill no)
			(layer "F.CrtYd")
		)
		(fp_rect
			(start -1.0922 2.3114)
			(end 1.0922 -2.3114)
			(stroke
				(width 0)
				(type default)
			)
			(fill no)
			(layer "F.Fab")
		)
		(pad "1" smd rect
			(at 0 -1.397 180)
			(size 1.651 1.27)
			(layers "F.Cu" "F.Mask" "F.Paste")
			(net "P12V")
		)
		(pad "2" smd rect
			(at 0 1.397 180)
			(size 1.651 1.27)
			(layers "F.Cu" "F.Mask" "F.Paste")
			(net "P12V_SLOT3")
		)
	)
)
